# BASEBOARD_FAB2 (Tioga Pass) — schematic netlist excerpt (pin names and nets, part order shuffled) for the footprints in the layout excerpt that follows; sources: Cadence DE-HDL packaged netlist, KiCad conversion of Wiwynn_Tioga_Pass_MB.brd

C4T5  CAP  10UF 4V 20% X6S  pkg 0603LF  page 231 : A = PVPP_ABC ; B = GND
R4T7  RES  665 1.0% CHIP  pkg 0402  page 99 : A = PVPP_ABC ; B = SMB_DDR_ABC_VPP_SCL_R
R9G33  RES  0.0 5% CHIP  pkg 0402  page 152 : A = H_CPU0_DEF_MEMHOT_LVT3_R_N ; B = H_CPU0_MEMDEF_MEMHOT_LVT3_K_N

(kicad_pcb
	(version 20260206)
	(generator "pcbnew")
	(generator_version "10.0")
	(general
		(thickness 1.6)
		(legacy_teardrops no)
	)
	(paper "A4")
	(title_block
		(title "Wiwynn_Tioga_Pass_MB.brd")
		(comment 1 "Tioga Pass / footprints 4451-4453 of 4770")
	)
	(layers
		(0 "F.Cu" signal "TOP")
		(4 "In1.Cu" signal "L2GND")
		(6 "In2.Cu" signal "L3")
		(8 "In3.Cu" signal "L4GND")
		(10 "In4.Cu" signal "L5")
		(12 "In5.Cu" signal "L6GND")
		(14 "In6.Cu" signal "L7VCC")
		(16 "In7.Cu" signal "L8VCC")
		(18 "In8.Cu" signal "L9GND")
		(20 "In9.Cu" signal "L10")
		(22 "In10.Cu" signal "L11GND")
		(24 "In11.Cu" signal "L12")
		(26 "In12.Cu" signal "L13GND")
		(2 "B.Cu" signal "BOTTOM")
		(9 "F.Adhes" user "F.Adhesive")
		(11 "B.Adhes" user "B.Adhesive")
		(13 "F.Paste" user "Package Geometry/Pastemask Top")
		(15 "B.Paste" user "Package Geometry/Pastemask Bottom")
		(5 "F.SilkS" user "Ref Des/Silkscreen Top")
		(7 "B.SilkS" user "Ref Des/Silkscreen Bottom")
		(1 "F.Mask" user "Board Geometry/Soldermask Top")
		(3 "B.Mask" user "Board Geometry/Soldermask Bottom")
		(17 "Dwgs.User" user "User.Drawings")
		(19 "Cmts.User" user "User.Comments")
		(21 "Eco1.User" user "User.Eco1")
		(23 "Eco2.User" user "User.Eco2")
		(25 "Edge.Cuts" user "Board Geometry/Outline")
		(27 "Margin" user)
		(31 "F.CrtYd" user "Package Geometry/Place Bound Top")
		(29 "B.CrtYd" user "Package Geometry/Place Bound Bottom")
		(35 "F.Fab" user "Ref Des/Assembly Top")
		(33 "B.Fab" user "Ref Des/Assembly Bottom")
	)
	(footprint ""
		(layer "B.Cu")
		(at 323.8627 -28.36418 -90)
		(property "Reference" "R4T7"
			(at 0 0 90)
			(layer "B.SilkS")
			(hide yes)
			(effects
				(font
					(size 1.27 1.27)
				)
				(justify mirror)
			)
		)
		(property "Value" ""
			(at 0 0 90)
			(layer "B.Fab")
			(effects
				(font
					(size 1.27 1.27)
				)
				(justify mirror)
			)
		)
		(duplicate_pad_numbers_are_jumpers no)
		(fp_poly
			(pts
				(xy 0.2794 -0.1016) (xy -0.2794 -0.1016) (xy -0.2794 0.9906) (xy 0.2794 0.9906)
			)
			(stroke
				(width 0)
				(type default)
			)
			(fill no)
			(layer "B.CrtYd")
		)
		(fp_line
			(start -0.2794 0.9906)
			(end -0.2794 -0.1016)
			(stroke
				(width 0.1)
				(type default)
			)
			(layer "B.Fab")
		)
		(fp_line
			(start 0.2794 0.9906)
			(end -0.2794 0.9906)
			(stroke
				(width 0.1)
				(type default)
			)
			(layer "B.Fab")
		)
		(fp_line
			(start -0.2794 -0.1016)
			(end 0.2794 -0.1016)
			(stroke
				(width 0.1)
				(type default)
			)
			(layer "B.Fab")
		)
		(fp_line
			(start 0.2794 -0.1016)
			(end 0.2794 0.9906)
			(stroke
				(width 0.1)
				(type default)
			)
			(layer "B.Fab")
		)
		(pad "1" smd rect
			(at 0 0 90)
			(size 0.508 0.508)
			(layers "B.Cu" "B.Mask" "B.Paste")
			(net "PVPP_ABC")
		)
		(pad "2" smd rect
			(at 0 0.889 90)
			(size 0.508 0.508)
			(layers "B.Cu" "B.Mask" "B.Paste")
			(net "SMB_DDR_ABC_VPP_SCL_R")
		)
		(zone
			(layer "B.Cu")
			(hatch none 0.5)
			(connect_pads
				(clearance 0)
			)
			(min_thickness 0.25)
			(keepout
				(tracks not_allowed)
				(vias allowed)
				(pads allowed)
				(copperpour not_allowed)
				(footprints allowed)
			)
			(placement
				(enabled no)
				(sheetname "")
			)
			(fill
				(thermal_gap 0.5)
				(thermal_bridge_width 0.5)
				(island_removal_mode 0)
			)
			(polygon
				(pts
					(xy 323.2277 -28.11018) (xy 323.2277 -28.61818) (xy 323.6087 -28.61818) (xy 323.6087 -28.11018)
				)
			)
		)
		(zone
			(layer "B.Cu")
			(hatch none 0.5)
			(connect_pads
				(clearance 0)
			)
			(min_thickness 0.25)
			(keepout
				(tracks allowed)
				(vias not_allowed)
				(pads allowed)
				(copperpour not_allowed)
				(footprints allowed)
			)
			(placement
				(enabled no)
				(sheetname "")
			)
			(fill
				(thermal_gap 0.5)
				(thermal_bridge_width 0.5)
				(island_removal_mode 0)
			)
			(polygon
				(pts
					(xy 323.6087 -28.11018) (xy 323.6087 -28.61818) (xy 323.2277 -28.61818) (xy 323.2277 -28.11018)
				)
			)
		)
	)
	(footprint ""
		(layer "B.Cu")
		(at 430.0855 -13.716 -90)
		(property "Reference" "R9G33"
			(at 0 0 90)
			(layer "B.SilkS")
			(hide yes)
			(effects
				(font
					(size 1.27 1.27)
				)
				(justify mirror)
			)
		)
		(property "Value" ""
			(at 0 0 90)
			(layer "B.Fab")
			(effects
				(font
					(size 1.27 1.27)
				)
				(justify mirror)
			)
		)
		(duplicate_pad_numbers_are_jumpers no)
		(fp_poly
			(pts
				(xy 0.2794 -0.1016) (xy -0.2794 -0.1016) (xy -0.2794 0.9906) (xy 0.2794 0.9906)
			)
			(stroke
				(width 0)
				(type default)
			)
			(fill no)
			(layer "B.CrtYd")
		)
		(fp_line
			(start -0.2794 0.9906)
			(end -0.2794 -0.1016)
			(stroke
				(width 0.1)
				(type default)
			)
			(layer "B.Fab")
		)
		(fp_line
			(start 0.2794 0.9906)
			(end -0.2794 0.9906)
			(stroke
				(width 0.1)
				(type default)
			)
			(layer "B.Fab")
		)
		(fp_line
			(start -0.2794 -0.1016)
			(end 0.2794 -0.1016)
			(stroke
				(width 0.1)
				(type default)
			)
			(layer "B.Fab")
		)
		(fp_line
			(start 0.2794 -0.1016)
			(end 0.2794 0.9906)
			(stroke
				(width 0.1)
				(type default)
			)
			(layer "B.Fab")
		)
		(pad "1" smd rect
			(at 0 0 90)
			(size 0.508 0.508)
			(layers "B.Cu" "B.Mask" "B.Paste")
			(net "H_CPU0_DEF_MEMHOT_LVT3_R_N")
		)
		(pad "2" smd rect
			(at 0 0.889 90)
			(size 0.508 0.508)
			(layers "B.Cu" "B.Mask" "B.Paste")
			(net "H_CPU0_MEMDEF_MEMHOT_LVT3_K_N")
		)
		(zone
			(layer "B.Cu")
			(hatch none 0.5)
			(connect_pads
				(clearance 0)
			)
			(min_thickness 0.25)
			(keepout
				(tracks not_allowed)
				(vias allowed)
				(pads allowed)
				(copperpour not_allowed)
				(footprints allowed)
			)
			(placement
				(enabled no)
				(sheetname "")
			)
			(fill
				(thermal_gap 0.5)
				(thermal_bridge_width 0.5)
				(island_removal_mode 0)
			)
			(polygon
				(pts
					(xy 429.4505 -13.462) (xy 429.4505 -13.97) (xy 429.8315 -13.97) (xy 429.8315 -13.462)
				)
			)
		)
		(zone
			(layer "B.Cu")
			(hatch none 0.5)
			(connect_pads
				(clearance 0)
			)
			(min_thickness 0.25)
			(keepout
				(tracks allowed)
				(vias not_allowed)
				(pads allowed)
				(copperpour not_allowed)
				(footprints allowed)
			)
			(placement
				(enabled no)
				(sheetname "")
			)
			(fill
				(thermal_gap 0.5)
				(thermal_bridge_width 0.5)
				(island_removal_mode 0)
			)
			(polygon
				(pts
					(xy 429.8315 -13.462) (xy 429.8315 -13.97) (xy 429.4505 -13.97) (xy 429.4505 -13.462)
				)
			)
		)
	)
	(footprint ""
		(layer "B.Cu")
		(at 320.194432 -17.78 90)
		(property "Reference" "C4T5"
			(at 0 0 90)
			(layer "B.SilkS")
			(hide yes)
			(effects
				(font
					(size 1.27 1.27)
				)
				(justify mirror)
			)
		)
		(property "Value" ""
			(at 0 0 90)
			(layer "B.Fab")
			(effects
				(font
					(size 1.27 1.27)
				)
				(justify mirror)
			)
		)
		(duplicate_pad_numbers_are_jumpers no)
		(fp_poly
			(pts
				(xy 0.4953 -0.2032) (xy -0.4953 -0.2032) (xy -0.4953 1.6002) (xy 0.4953 1.6002)
			)
			(stroke
				(width 0)
				(type default)
			)
			(fill no)
			(layer "B.CrtYd")
		)
		(fp_line
			(start 0.4953 -0.2032)
			(end -0.4953 -0.2032)
			(stroke
				(width 0.1)
				(type default)
			)
			(layer "B.Fab")
		)
		(fp_line
			(start -0.4953 -0.2032)
			(end -0.4953 1.6002)
			(stroke
				(width 0.1)
				(type default)
			)
			(layer "B.Fab")
		)
		(fp_line
			(start 0.4953 1.6002)
			(end 0.4953 -0.2032)
			(stroke
				(width 0.1)
				(type default)
			)
			(layer "B.Fab")
		)
		(fp_line
			(start -0.4953 1.6002)
			(end 0.4953 1.6002)
			(stroke
				(width 0.1)
				(type default)
			)
			(layer "B.Fab")
		)
		(pad "1" smd rect
			(at 0 0 270)
			(size 0.762 0.889)
			(layers "B.Cu" "B.Mask" "B.Paste")
			(net "PVPP_ABC")
		)
		(pad "2" smd rect
			(at 0 1.397 270)
			(size 0.762 0.889)
			(layers "B.Cu" "B.Mask" "B.Paste")
			(net "GND")
		)
		(zone
			(layer "B.Cu")
			(hatch none 0.5)
			(connect_pads
				(clearance 0)
			)
			(min_thickness 0.25)
			(keepout
				(tracks not_allowed)
				(vias allowed)
				(pads allowed)
				(copperpour not_allowed)
				(footprints allowed)
			)
			(placement
				(enabled no)
				(sheetname "")
			)
			(fill
				(thermal_gap 0.5)
				(thermal_bridge_width 0.5)
				(island_removal_mode 0)
			)
			(polygon
				(pts
					(xy 320.638932 -18.161) (xy 320.638932 -17.399) (xy 321.146932 -17.399) (xy 321.146932 -18.161)
				)
			)
		)
	)
)
